# BASEBOARD_FAB2 (Tioga Pass) — schematic netlist excerpt (pin names and nets, part order shuffled) for the footprints in the layout excerpt that follows; sources: Cadence DE-HDL packaged netlist, KiCad conversion of Wiwynn_Tioga_Pass_MB.brd

C3D1  CAP_A  22.0UF 4V 20% X6S  pkg 0603V  page 228 : A = PVDDQ_KLM ; B = GND
R1C37  RES  68.1K 1% EMPTY  pkg 0402  page 210 : A = VR_PVSA_CPU1_OCSET ; B = GND
R4D47  RES  0.0 5% CHIP  pkg 0402  page 213 : A = P3V3_STBY ; B = VR_PVCCIO_CPU1_VDD

(kicad_pcb
	(version 20260206)
	(generator "pcbnew")
	(generator_version "10.0")
	(general
		(thickness 1.6)
		(legacy_teardrops no)
	)
	(paper "A4")
	(title_block
		(title "Wiwynn_Tioga_Pass_MB.brd")
		(comment 1 "Tioga Pass / footprints 1969-1971 of 4770")
	)
	(layers
		(0 "F.Cu" signal "TOP")
		(4 "In1.Cu" signal "L2GND")
		(6 "In2.Cu" signal "L3")
		(8 "In3.Cu" signal "L4GND")
		(10 "In4.Cu" signal "L5")
		(12 "In5.Cu" signal "L6GND")
		(14 "In6.Cu" signal "L7VCC")
		(16 "In7.Cu" signal "L8VCC")
		(18 "In8.Cu" signal "L9GND")
		(20 "In9.Cu" signal "L10")
		(22 "In10.Cu" signal "L11GND")
		(24 "In11.Cu" signal "L12")
		(26 "In12.Cu" signal "L13GND")
		(2 "B.Cu" signal "BOTTOM")
		(9 "F.Adhes" user "F.Adhesive")
		(11 "B.Adhes" user "B.Adhesive")
		(13 "F.Paste" user "Package Geometry/Pastemask Top")
		(15 "B.Paste" user "Package Geometry/Pastemask Bottom")
		(5 "F.SilkS" user "Ref Des/Silkscreen Top")
		(7 "B.SilkS" user "Ref Des/Silkscreen Bottom")
		(1 "F.Mask" user "Board Geometry/Soldermask Top")
		(3 "B.Mask" user "Board Geometry/Soldermask Bottom")
		(17 "Dwgs.User" user "User.Drawings")
		(19 "Cmts.User" user "User.Comments")
		(21 "Eco1.User" user "User.Eco1")
		(23 "Eco2.User" user "User.Eco2")
		(25 "Edge.Cuts" user "Board Geometry/Outline")
		(27 "Margin" user)
		(31 "F.CrtYd" user "Package Geometry/Place Bound Top")
		(29 "B.CrtYd" user "Package Geometry/Place Bound Bottom")
		(35 "F.Fab" user "Ref Des/Assembly Top")
		(33 "B.Fab" user "Ref Des/Assembly Bottom")
	)
	(footprint ""
		(layer "F.Cu")
		(at 28.85948 -96.19234 -90)
		(property "Reference" "R1C37"
			(at 0 0 270)
			(layer "F.SilkS")
			(hide yes)
			(effects
				(font
					(size 1.27 1.27)
				)
			)
		)
		(property "Value" ""
			(at 0 0 270)
			(layer "F.Fab")
			(effects
				(font
					(size 1.27 1.27)
				)
			)
		)
		(duplicate_pad_numbers_are_jumpers no)
		(fp_poly
			(pts
				(xy -0.2794 -0.1016) (xy 0.2794 -0.1016) (xy 0.2794 0.9906) (xy -0.2794 0.9906)
			)
			(stroke
				(width 0)
				(type default)
			)
			(fill no)
			(layer "F.CrtYd")
		)
		(fp_line
			(start -0.2794 0.9906)
			(end 0.2794 0.9906)
			(stroke
				(width 0.1)
				(type default)
			)
			(layer "F.Fab")
		)
		(fp_line
			(start 0.2794 0.9906)
			(end 0.2794 -0.1016)
			(stroke
				(width 0.1)
				(type default)
			)
			(layer "F.Fab")
		)
		(fp_line
			(start -0.2794 -0.1016)
			(end -0.2794 0.9906)
			(stroke
				(width 0.1)
				(type default)
			)
			(layer "F.Fab")
		)
		(fp_line
			(start 0.2794 -0.1016)
			(end -0.2794 -0.1016)
			(stroke
				(width 0.1)
				(type default)
			)
			(layer "F.Fab")
		)
		(pad "1" smd rect
			(at 0 0 270)
			(size 0.508 0.508)
			(layers "F.Cu" "F.Mask" "F.Paste")
			(net "VR_PVSA_CPU1_OCSET")
		)
		(pad "2" smd rect
			(at 0 0.889 270)
			(size 0.508 0.508)
			(layers "F.Cu" "F.Mask" "F.Paste")
			(net "GND")
		)
		(zone
			(layer "F.Cu")
			(hatch none 0.5)
			(connect_pads
				(clearance 0)
			)
			(min_thickness 0.25)
			(keepout
				(tracks not_allowed)
				(vias allowed)
				(pads allowed)
				(copperpour not_allowed)
				(footprints allowed)
			)
			(placement
				(enabled no)
				(sheetname "")
			)
			(fill
				(thermal_gap 0.5)
				(thermal_bridge_width 0.5)
				(island_removal_mode 0)
			)
			(polygon
				(pts
					(xy 28.22448 -96.44634) (xy 28.22448 -95.93834) (xy 28.60548 -95.93834) (xy 28.60548 -96.44634)
				)
			)
		)
		(zone
			(layer "F.Cu")
			(hatch none 0.5)
			(connect_pads
				(clearance 0)
			)
			(min_thickness 0.25)
			(keepout
				(tracks allowed)
				(vias not_allowed)
				(pads allowed)
				(copperpour not_allowed)
				(footprints allowed)
			)
			(placement
				(enabled no)
				(sheetname "")
			)
			(fill
				(thermal_gap 0.5)
				(thermal_bridge_width 0.5)
				(island_removal_mode 0)
			)
			(polygon
				(pts
					(xy 28.60548 -96.44634) (xy 28.60548 -95.93834) (xy 28.22448 -95.93834) (xy 28.22448 -96.44634)
				)
			)
		)
	)
	(footprint ""
		(layer "F.Cu")
		(at 107.240578 -84.890102)
		(property "Reference" "C3D1"
			(at 0 0 0)
			(layer "F.SilkS")
			(hide yes)
			(effects
				(font
					(size 1.27 1.27)
				)
			)
		)
		(property "Value" ""
			(at 0 0 0)
			(layer "F.Fab")
			(effects
				(font
					(size 1.27 1.27)
				)
			)
		)
		(duplicate_pad_numbers_are_jumpers no)
		(fp_poly
			(pts
				(xy -0.4953 -0.2032) (xy 0.4953 -0.2032) (xy 0.4953 1.6002) (xy -0.4953 1.6002)
			)
			(stroke
				(width 0)
				(type default)
			)
			(fill no)
			(layer "F.CrtYd")
		)
		(fp_line
			(start -0.4953 -0.2032)
			(end 0.4953 -0.2032)
			(stroke
				(width 0.1)
				(type default)
			)
			(layer "F.Fab")
		)
		(fp_line
			(start -0.4953 1.6002)
			(end -0.4953 -0.2032)
			(stroke
				(width 0.1)
				(type default)
			)
			(layer "F.Fab")
		)
		(fp_line
			(start 0.4953 -0.2032)
			(end 0.4953 1.6002)
			(stroke
				(width 0.1)
				(type default)
			)
			(layer "F.Fab")
		)
		(fp_line
			(start 0.4953 1.6002)
			(end -0.4953 1.6002)
			(stroke
				(width 0.1)
				(type default)
			)
			(layer "F.Fab")
		)
		(pad "1" smd rect
			(at 0 0)
			(size 0.762 0.889)
			(layers "F.Cu" "F.Mask" "F.Paste")
			(net "PVDDQ_KLM")
		)
		(pad "2" smd rect
			(at 0 1.397)
			(size 0.762 0.889)
			(layers "F.Cu" "F.Mask" "F.Paste")
			(net "GND")
		)
		(zone
			(layer "F.Cu")
			(hatch none 0.5)
			(connect_pads
				(clearance 0)
			)
			(min_thickness 0.25)
			(keepout
				(tracks not_allowed)
				(vias allowed)
				(pads allowed)
				(copperpour not_allowed)
				(footprints allowed)
			)
			(placement
				(enabled no)
				(sheetname "")
			)
			(fill
				(thermal_gap 0.5)
				(thermal_bridge_width 0.5)
				(island_removal_mode 0)
			)
			(polygon
				(pts
					(xy 106.859578 -84.445602) (xy 107.621578 -84.445602) (xy 107.621578 -83.937602) (xy 106.859578 -83.937602)
				)
			)
		)
	)
	(footprint ""
		(layer "F.Cu")
		(at 174.6377 -70.612 -90)
		(property "Reference" "R4D47"
			(at 0 0 270)
			(layer "F.SilkS")
			(hide yes)
			(effects
				(font
					(size 1.27 1.27)
				)
			)
		)
		(property "Value" ""
			(at 0 0 270)
			(layer "F.Fab")
			(effects
				(font
					(size 1.27 1.27)
				)
			)
		)
		(duplicate_pad_numbers_are_jumpers no)
		(fp_poly
			(pts
				(xy -0.2794 -0.1016) (xy 0.2794 -0.1016) (xy 0.2794 0.9906) (xy -0.2794 0.9906)
			)
			(stroke
				(width 0)
				(type default)
			)
			(fill no)
			(layer "F.CrtYd")
		)
		(fp_line
			(start -0.2794 0.9906)
			(end 0.2794 0.9906)
			(stroke
				(width 0.1)
				(type default)
			)
			(layer "F.Fab")
		)
		(fp_line
			(start 0.2794 0.9906)
			(end 0.2794 -0.1016)
			(stroke
				(width 0.1)
				(type default)
			)
			(layer "F.Fab")
		)
		(fp_line
			(start -0.2794 -0.1016)
			(end -0.2794 0.9906)
			(stroke
				(width 0.1)
				(type default)
			)
			(layer "F.Fab")
		)
		(fp_line
			(start 0.2794 -0.1016)
			(end -0.2794 -0.1016)
			(stroke
				(width 0.1)
				(type default)
			)
			(layer "F.Fab")
		)
		(pad "1" smd rect
			(at 0 0 270)
			(size 0.508 0.508)
			(layers "F.Cu" "F.Mask" "F.Paste")
			(net "P3V3_STBY")
		)
		(pad "2" smd rect
			(at 0 0.889 270)
			(size 0.508 0.508)
			(layers "F.Cu" "F.Mask" "F.Paste")
			(net "VR_PVCCIO_CPU1_VDD")
		)
		(zone
			(layer "F.Cu")
			(hatch none 0.5)
			(connect_pads
				(clearance 0)
			)
			(min_thickness 0.25)
			(keepout
				(tracks not_allowed)
				(vias allowed)
				(pads allowed)
				(copperpour not_allowed)
				(footprints allowed)
			)
			(placement
				(enabled no)
				(sheetname "")
			)
			(fill
				(thermal_gap 0.5)
				(thermal_bridge_width 0.5)
				(island_removal_mode 0)
			)
			(polygon
				(pts
					(xy 174.0027 -70.866) (xy 174.0027 -70.358) (xy 174.3837 -70.358) (xy 174.3837 -70.866)
				)
			)
		)
		(zone
			(layer "F.Cu")
			(hatch none 0.5)
			(connect_pads
				(clearance 0)
			)
			(min_thickness 0.25)
			(keepout
				(tracks allowed)
				(vias not_allowed)
				(pads allowed)
				(copperpour not_allowed)
				(footprints allowed)
			)
			(placement
				(enabled no)
				(sheetname "")
			)
			(fill
				(thermal_gap 0.5)
				(thermal_bridge_width 0.5)
				(island_removal_mode 0)
			)
			(polygon
				(pts
					(xy 174.3837 -70.866) (xy 174.3837 -70.358) (xy 174.0027 -70.358) (xy 174.0027 -70.866)
				)
			)
		)
	)
)
